(kicad_pcb
	(version 20260206)
	(generator "pcbnew")
	(generator_version "10.0")
	(general
		(thickness 1.6)
		(legacy_teardrops no)
	)
	(paper "A4")
	(title_block
		(title "dpb — 14545-sa.0730WZS0815.brd")
		(comment 1 "Honey Badger (Wiwynn) / footprints 237-244 of 1066")
	)
	(layers
		(0 "F.Cu" signal "TOP")
		(4 "In1.Cu" signal "L2GND")
		(6 "In2.Cu" signal "L3")
		(8 "In3.Cu" signal "L4VCC")
		(10 "In4.Cu" signal "L5VCC")
		(12 "In5.Cu" signal "L6")
		(14 "In6.Cu" signal "L7GND")
		(2 "B.Cu" signal "BOTTOM")
		(9 "F.Adhes" user "F.Adhesive")
		(11 "B.Adhes" user "B.Adhesive")
		(13 "F.Paste" user "Package Geometry/Pastemask Top")
		(15 "B.Paste" user "Package Geometry/Pastemask Bottom")
		(5 "F.SilkS" user "Ref Des/Silkscreen Top")
		(7 "B.SilkS" user "Ref Des/Silkscreen Bottom")
		(1 "F.Mask" user "Board Geometry/Soldermask Top")
		(3 "B.Mask" user "Board Geometry/Soldermask Bottom")
		(17 "Dwgs.User" user "User.Drawings")
		(19 "Cmts.User" user "User.Comments")
		(21 "Eco1.User" user "User.Eco1")
		(23 "Eco2.User" user "User.Eco2")
		(25 "Edge.Cuts" user "Board Geometry/Outline")
		(27 "Margin" user)
		(31 "F.CrtYd" user "Package Geometry/Place Bound Top")
		(29 "B.CrtYd" user "Package Geometry/Place Bound Bottom")
		(35 "F.Fab" user "Ref Des/Assembly Top")
		(33 "B.Fab" user "Ref Des/Assembly Bottom")
	)
	(footprint ""
		(layer "F.Cu")
		(at 78.485746 -184.5437)
		(property "Reference" "C235"
			(at 0 0 0)
			(layer "F.SilkS")
			(hide yes)
			(effects
				(font
					(size 1.27 1.27)
				)
			)
		)
		(property "Value" "SCD1U10V2KX-5GP"
			(at 1.1811 -2.7051 0)
			(unlocked yes)
			(layer "F.Fab")
			(hide yes)
			(effects
				(font
					(size 1.016 1.016)
					(thickness 0.1524)
				)
			)
		)
		(property "Device Type" "C402H22"
			(at 1.1811 -4.2291 0)
			(unlocked yes)
			(layer "F.Fab")
			(hide yes)
			(effects
				(font
					(size 1.016 1.016)
					(thickness 0.1524)
				)
			)
		)
		(duplicate_pad_numbers_are_jumpers no)
		(fp_rect
			(start -0.4318 0.9525)
			(end 0.4318 -0.9525)
			(stroke
				(width 0)
				(type default)
			)
			(fill no)
			(layer "F.CrtYd")
		)
		(fp_rect
			(start -0.4318 0.9525)
			(end 0.4318 -0.9525)
			(stroke
				(width 0)
				(type default)
			)
			(fill no)
			(layer "F.Fab")
		)
		(pad "1" smd custom
			(at 0 -0.4445)
			(size 0.1524 0.1524)
			(layers "F.Cu" "F.Mask" "F.Paste")
			(net "P3V3")
			(options
				(clearance outline)
				(anchor circle)
			)
			(primitives
				(gr_poly
					(pts
						(arc
							(start 0.3048 -0.2032)
							(mid 0.275042 -0.275042)
							(end 0.2032 -0.3048)
						)
						(arc
							(start -0.2032 -0.3048)
							(mid -0.275042 -0.275042)
							(end -0.3048 -0.2032)
						)
						(arc
							(start -0.3048 0.2032)
							(mid -0.275042 0.275042)
							(end -0.2032 0.3048)
						)
						(arc
							(start 0.2032 0.3048)
							(mid 0.275042 0.275042)
							(end 0.3048 0.2032)
						)
					)
					(width 0)
					(fill yes)
				)
			)
		)
		(pad "2" smd custom
			(at 0 0.4445)
			(size 0.1524 0.1524)
			(layers "F.Cu" "F.Mask" "F.Paste")
			(net "GND")
			(options
				(clearance outline)
				(anchor circle)
			)
			(primitives
				(gr_poly
					(pts
						(arc
							(start 0.3048 -0.2032)
							(mid 0.275042 -0.275042)
							(end 0.2032 -0.3048)
						)
						(arc
							(start -0.2032 -0.3048)
							(mid -0.275042 -0.275042)
							(end -0.3048 -0.2032)
						)
						(arc
							(start -0.3048 0.2032)
							(mid -0.275042 0.275042)
							(end -0.2032 0.3048)
						)
						(arc
							(start 0.2032 0.3048)
							(mid 0.275042 0.275042)
							(end 0.3048 0.2032)
						)
					)
					(width 0)
					(fill yes)
				)
			)
		)
	)
	(footprint ""
		(layer "F.Cu")
		(at 77.978 -25.7556)
		(property "Reference" "Q75"
			(at 0 0 0)
			(layer "F.SilkS")
			(hide yes)
			(effects
				(font
					(size 1.27 1.27)
				)
			)
		)
		(property "Value" "2N7002-11-GP"
			(at 0.127 -8.9662 0)
			(unlocked yes)
			(layer "F.Fab")
			(hide yes)
			(effects
				(font
					(size 1.016 1.016)
					(thickness 0.1524)
				)
			)
		)
		(property "Device Type" "SOT23DGS2D4H44"
			(at 0.127 -10.4902 0)
			(unlocked yes)
			(layer "F.Fab")
			(hide yes)
			(effects
				(font
					(size 1.016 1.016)
					(thickness 0.1524)
				)
			)
		)
		(duplicate_pad_numbers_are_jumpers no)
		(fp_line
			(start -1.651 -1.778)
			(end -1.651 1.778)
			(stroke
				(width 0.1524)
				(type default)
			)
			(layer "F.SilkS")
		)
		(fp_line
			(start -1.651 1.778)
			(end 1.651 1.778)
			(stroke
				(width 0.1524)
				(type default)
			)
			(layer "F.SilkS")
		)
		(fp_line
			(start 1.651 -1.778)
			(end -1.651 -1.778)
			(stroke
				(width 0.1524)
				(type default)
			)
			(layer "F.SilkS")
		)
		(fp_line
			(start 1.651 1.778)
			(end 1.651 -1.778)
			(stroke
				(width 0.1524)
				(type default)
			)
			(layer "F.SilkS")
		)
		(fp_poly
			(pts
				(xy -1.778 1.8796) (xy -1.778 -1.8796) (xy 1.778 -1.8796) (xy 1.778 1.8796)
			)
			(stroke
				(width 0)
				(type default)
			)
			(fill no)
			(layer "F.CrtYd")
		)
		(fp_poly
			(pts
				(xy -1.778 1.8796) (xy -1.778 -1.8796) (xy 1.778 -1.8796) (xy 1.778 1.8796)
			)
			(stroke
				(width 0)
				(type default)
			)
			(fill no)
			(layer "F.Fab")
		)
		(pad "D" smd custom
			(at 0 -0.9525)
			(size 0.1905 0.1905)
			(layers "F.Cu" "F.Mask" "F.Paste")
			(net "HDD14_LED_G")
			(options
				(clearance outline)
				(anchor circle)
			)
			(primitives
				(gr_poly
					(pts
						(arc
							(start -0.1778 0.5715)
							(mid -0.321484 0.511984)
							(end -0.381 0.3683)
						)
						(arc
							(start -0.381 -0.3683)
							(mid -0.321484 -0.511984)
							(end -0.1778 -0.5715)
						)
						(arc
							(start 0.1778 -0.5715)
							(mid 0.321484 -0.511984)
							(end 0.381 -0.3683)
						)
						(arc
							(start 0.381 0.3683)
							(mid 0.321484 0.511984)
							(end 0.1778 0.5715)
						)
					)
					(width 0)
					(fill yes)
				)
			)
		)
		(pad "G" smd custom
			(at -0.98425 0.9525)
			(size 0.1905 0.1905)
			(layers "F.Cu" "F.Mask" "F.Paste")
			(net "HDD14_LED_B")
			(options
				(clearance outline)
				(anchor circle)
			)
			(primitives
				(gr_poly
					(pts
						(arc
							(start -0.1778 0.5715)
							(mid -0.321484 0.511984)
							(end -0.381 0.3683)
						)
						(arc
							(start -0.381 -0.3683)
							(mid -0.321484 -0.511984)
							(end -0.1778 -0.5715)
						)
						(arc
							(start 0.1778 -0.5715)
							(mid 0.321484 -0.511984)
							(end 0.381 -0.3683)
						)
						(arc
							(start 0.381 0.3683)
							(mid 0.321484 0.511984)
							(end 0.1778 0.5715)
						)
					)
					(width 0)
					(fill yes)
				)
			)
		)
		(pad "S" smd custom
			(at 0.98425 0.9525)
			(size 0.1905 0.1905)
			(layers "F.Cu" "F.Mask" "F.Paste")
			(net "GND")
			(options
				(clearance outline)
				(anchor circle)
			)
			(primitives
				(gr_poly
					(pts
						(arc
							(start -0.1778 0.5715)
							(mid -0.321484 0.511984)
							(end -0.381 0.3683)
						)
						(arc
							(start -0.381 -0.3683)
							(mid -0.321484 -0.511984)
							(end -0.1778 -0.5715)
						)
						(arc
							(start 0.1778 -0.5715)
							(mid 0.321484 -0.511984)
							(end 0.381 -0.3683)
						)
						(arc
							(start 0.381 0.3683)
							(mid 0.321484 0.511984)
							(end 0.1778 0.5715)
						)
					)
					(width 0)
					(fill yes)
				)
			)
		)
	)
	(footprint ""
		(layer "F.Cu")
		(at 242.569746 -20.8407 90)
		(property "Reference" "PC2"
			(at 0 0 90)
			(layer "F.SilkS")
			(hide yes)
			(effects
				(font
					(size 1.27 1.27)
				)
			)
		)
		(property "Value" "SC22U25V5MX-GP"
			(at -0.0762 -6.1214 90)
			(unlocked yes)
			(layer "F.Fab")
			(hide yes)
			(effects
				(font
					(size 1.016 1.016)
					(thickness 0.1524)
				)
			)
		)
		(property "Device Type" "C805H58"
			(at -0.0762 -8.1534 90)
			(unlocked yes)
			(layer "F.Fab")
			(hide yes)
			(effects
				(font
					(size 1.016 1.016)
					(thickness 0.1524)
				)
			)
		)
		(duplicate_pad_numbers_are_jumpers no)
		(fp_line
			(start 0.635 0)
			(end -0.635 0)
			(stroke
				(width 0.508)
				(type default)
			)
			(layer "F.SilkS")
		)
		(fp_rect
			(start -0.9652 1.778)
			(end 0.9652 -1.778)
			(stroke
				(width 0)
				(type default)
			)
			(fill no)
			(layer "F.CrtYd")
		)
		(fp_poly
			(pts
				(xy -0.9652 -1.778) (xy 0.9652 -1.778) (xy 0.9652 1.778) (xy -0.9652 1.778)
			)
			(stroke
				(width 0)
				(type default)
			)
			(fill no)
			(layer "F.Fab")
		)
		(pad "1" smd rect
			(at 0 -0.9652 90)
			(size 1.397 1.143)
			(layers "F.Cu" "F.Mask" "F.Paste")
			(net "P5VA_12VIN")
		)
		(pad "2" smd rect
			(at 0 0.9652 90)
			(size 1.397 1.143)
			(layers "F.Cu" "F.Mask" "F.Paste")
			(net "GND")
		)
	)
	(footprint ""
		(layer "F.Cu")
		(at 46.837346 -450.3928 -90)
		(property "Reference" "R493"
			(at 0 0 270)
			(layer "F.SilkS")
			(hide yes)
			(effects
				(font
					(size 1.27 1.27)
				)
			)
		)
		(property "Value" "1KR2F-3-GP"
			(at 0.064008 -3.993896 270)
			(unlocked yes)
			(layer "F.Fab")
			(hide yes)
			(effects
				(font
					(size 1.016 1.016)
					(thickness 0.1524)
				)
			)
		)
		(property "Device Type" "R402H16"
			(at 0.064008 -5.517896 270)
			(unlocked yes)
			(layer "F.Fab")
			(hide yes)
			(effects
				(font
					(size 1.016 1.016)
					(thickness 0.1524)
				)
			)
		)
		(duplicate_pad_numbers_are_jumpers no)
		(fp_line
			(start -0.508 -0.9398)
			(end -0.508 0.9398)
			(stroke
				(width 0.1524)
				(type default)
			)
			(layer "F.SilkS")
		)
		(fp_line
			(start 0.508 -0.9398)
			(end -0.508 -0.9398)
			(stroke
				(width 0.1524)
				(type default)
			)
			(layer "F.SilkS")
		)
		(fp_rect
			(start -0.508 0.9398)
			(end 0.508 -0.9398)
			(stroke
				(width 0)
				(type default)
			)
			(fill no)
			(layer "F.CrtYd")
		)
		(fp_rect
			(start -0.508 0.9398)
			(end 0.508 -0.9398)
			(stroke
				(width 0)
				(type default)
			)
			(fill no)
			(layer "F.Fab")
		)
		(pad "1" smd custom
			(at 0 -0.4445 270)
			(size 0.1397 0.1397)
			(layers "F.Cu" "F.Mask" "F.Paste")
			(net "FLT_HDD5_B")
			(options
				(clearance outline)
				(anchor circle)
			)
			(primitives
				(gr_poly
					(pts
						(arc
							(start -0.1778 -0.2794)
							(mid -0.249642 -0.249642)
							(end -0.2794 -0.1778)
						)
						(arc
							(start -0.2794 0.1778)
							(mid -0.249642 0.249642)
							(end -0.1778 0.2794)
						)
						(arc
							(start 0.1778 0.2794)
							(mid 0.249642 0.249642)
							(end 0.2794 0.1778)
						)
						(arc
							(start 0.2794 -0.1778)
							(mid 0.249642 -0.249642)
							(end 0.1778 -0.2794)
						)
					)
					(width 0)
					(fill yes)
				)
			)
		)
		(pad "2" smd custom
			(at 0 0.4445 270)
			(size 0.1397 0.1397)
			(layers "F.Cu" "F.Mask" "F.Paste")
			(net "FLT_HDD5_DRIVE")
			(options
				(clearance outline)
				(anchor circle)
			)
			(primitives
				(gr_poly
					(pts
						(arc
							(start -0.1778 -0.2794)
							(mid -0.249642 -0.249642)
							(end -0.2794 -0.1778)
						)
						(arc
							(start -0.2794 0.1778)
							(mid -0.249642 0.249642)
							(end -0.1778 0.2794)
						)
						(arc
							(start 0.1778 0.2794)
							(mid 0.249642 0.249642)
							(end 0.2794 0.1778)
						)
						(arc
							(start 0.2794 -0.1778)
							(mid 0.249642 -0.249642)
							(end 0.1778 -0.2794)
						)
					)
					(width 0)
					(fill yes)
				)
			)
		)
	)
	(footprint ""
		(layer "F.Cu")
		(at 57.6072 -276.4282)
		(property "Reference" "R203"
			(at 0 0 0)
			(layer "F.SilkS")
			(hide yes)
			(effects
				(font
					(size 1.27 1.27)
				)
			)
		)
		(property "Value" "4K7R2J-2-GP"
			(at 0.064008 -3.993896 0)
			(unlocked yes)
			(layer "F.Fab")
			(hide yes)
			(effects
				(font
					(size 1.016 1.016)
					(thickness 0.1524)
				)
			)
		)
		(property "Device Type" "R402H16"
			(at 0.064008 -5.517896 0)
			(unlocked yes)
			(layer "F.Fab")
			(hide yes)
			(effects
				(font
					(size 1.016 1.016)
					(thickness 0.1524)
				)
			)
		)
		(duplicate_pad_numbers_are_jumpers no)
		(fp_line
			(start -0.508 -0.9398)
			(end -0.508 0.9398)
			(stroke
				(width 0.1524)
				(type default)
			)
			(layer "F.SilkS")
		)
		(fp_line
			(start 0.508 -0.9398)
			(end -0.508 -0.9398)
			(stroke
				(width 0.1524)
				(type default)
			)
			(layer "F.SilkS")
		)
		(fp_rect
			(start -0.508 0.9398)
			(end 0.508 -0.9398)
			(stroke
				(width 0)
				(type default)
			)
			(fill no)
			(layer "F.CrtYd")
		)
		(fp_rect
			(start -0.508 0.9398)
			(end 0.508 -0.9398)
			(stroke
				(width 0)
				(type default)
			)
			(fill no)
			(layer "F.Fab")
		)
		(pad "1" smd custom
			(at 0 -0.4445)
			(size 0.1397 0.1397)
			(layers "F.Cu" "F.Mask" "F.Paste")
			(net "P3V3")
			(options
				(clearance outline)
				(anchor circle)
			)
			(primitives
				(gr_poly
					(pts
						(arc
							(start -0.1778 -0.2794)
							(mid -0.249642 -0.249642)
							(end -0.2794 -0.1778)
						)
						(arc
							(start -0.2794 0.1778)
							(mid -0.249642 0.249642)
							(end -0.1778 0.2794)
						)
						(arc
							(start 0.1778 0.2794)
							(mid 0.249642 0.249642)
							(end 0.2794 0.1778)
						)
						(arc
							(start 0.2794 -0.1778)
							(mid 0.249642 -0.249642)
							(end 0.1778 -0.2794)
						)
					)
					(width 0)
					(fill yes)
				)
			)
		)
		(pad "2" smd custom
			(at 0 0.4445)
			(size 0.1397 0.1397)
			(layers "F.Cu" "F.Mask" "F.Paste")
			(net "HDD_PRSNT_NET7")
			(options
				(clearance outline)
				(anchor circle)
			)
			(primitives
				(gr_poly
					(pts
						(arc
							(start -0.1778 -0.2794)
							(mid -0.249642 -0.249642)
							(end -0.2794 -0.1778)
						)
						(arc
							(start -0.2794 0.1778)
							(mid -0.249642 0.249642)
							(end -0.1778 0.2794)
						)
						(arc
							(start 0.1778 0.2794)
							(mid 0.249642 0.249642)
							(end 0.2794 0.1778)
						)
						(arc
							(start 0.2794 -0.1778)
							(mid 0.249642 -0.249642)
							(end 0.1778 -0.2794)
						)
					)
					(width 0)
					(fill yes)
				)
			)
		)
	)
	(footprint ""
		(layer "F.Cu")
		(at 25.653746 -119.0117)
		(property "Reference" "TP38"
			(at 0 0 0)
			(layer "F.SilkS")
			(hide yes)
			(effects
				(font
					(size 1.27 1.27)
				)
			)
		)
		(property "Value" "TPAD32-GP"
			(at 0 -3.166364 0)
			(unlocked yes)
			(layer "F.Fab")
			(hide yes)
			(effects
				(font
					(size 1.016 1.016)
					(thickness 0.1524)
				)
			)
		)
		(property "Device Type" "TPAD32"
			(at 0 -4.690618 0)
			(unlocked yes)
			(layer "F.Fab")
			(hide yes)
			(effects
				(font
					(size 1.016 1.016)
					(thickness 0.1524)
				)
			)
		)
		(duplicate_pad_numbers_are_jumpers no)
		(fp_poly
			(pts
				(arc
					(start 0.4064 0)
					(mid -0.4064 0)
					(end 0.4064 0)
				)
			)
			(stroke
				(width 0)
				(type default)
			)
			(fill no)
			(layer "F.CrtYd")
		)
		(fp_poly
			(pts
				(arc
					(start 0.7112 0)
					(mid -0.7112 0)
					(end 0.7112 0)
				)
			)
			(stroke
				(width 0)
				(type default)
			)
			(fill no)
			(layer "F.Fab")
		)
		(pad "1" smd circle
			(at 0 0)
			(size 0.8128 0.8128)
			(layers "F.Cu" "F.Mask" "F.Paste")
			(net "ACT_HDD13")
		)
	)
	(footprint ""
		(layer "F.Cu")
		(at 215.6714 -497.713 180)
		(property "Reference" "C113"
			(at 0 0 180)
			(layer "F.SilkS")
			(hide yes)
			(effects
				(font
					(size 1.27 1.27)
				)
			)
		)
		(property "Value" "SC10U25V6KX-1GP"
			(at -0.0762 -5.1308 180)
			(unlocked yes)
			(layer "F.Fab")
			(hide yes)
			(effects
				(font
					(size 1.016 1.016)
					(thickness 0.1524)
				)
			)
		)
		(property "Device Type" "C1206H71"
			(at -0.127 -6.6548 180)
			(unlocked yes)
			(layer "F.Fab")
			(hide yes)
			(effects
				(font
					(size 1.016 1.016)
					(thickness 0.1524)
				)
			)
		)
		(duplicate_pad_numbers_are_jumpers no)
		(fp_line
			(start 1.016 2.2352)
			(end -1.016 2.2352)
			(stroke
				(width 0.1524)
				(type default)
			)
			(layer "F.SilkS")
		)
		(fp_line
			(start 1.016 0.8382)
			(end 1.016 2.2352)
			(stroke
				(width 0.1524)
				(type default)
			)
			(layer "F.SilkS")
		)
		(fp_line
			(start 1.016 -2.2352)
			(end 1.016 -0.8382)
			(stroke
				(width 0.1524)
				(type default)
			)
			(layer "F.SilkS")
		)
		(fp_line
			(start -1.016 2.2352)
			(end -1.016 0.8382)
			(stroke
				(width 0.1524)
				(type default)
			)
			(layer "F.SilkS")
		)
		(fp_line
			(start -1.016 -0.8382)
			(end -1.016 -2.2352)
			(stroke
				(width 0.1524)
				(type default)
			)
			(layer "F.SilkS")
		)
		(fp_line
			(start -1.016 -2.2352)
			(end 1.016 -2.2352)
			(stroke
				(width 0.1524)
				(type default)
			)
			(layer "F.SilkS")
		)
		(fp_rect
			(start -1.0922 2.3114)
			(end 1.0922 -2.3114)
			(stroke
				(width 0)
				(type default)
			)
			(fill no)
			(layer "F.CrtYd")
		)
		(fp_poly
			(pts
				(xy 1.0922 -2.3114) (xy 1.0922 2.3114) (xy -1.0922 2.3114) (xy -1.0922 -2.3114)
			)
			(stroke
				(width 0)
				(type default)
			)
			(fill no)
			(layer "F.Fab")
		)
		(pad "1" smd rect
			(at 0 -1.397 180)
			(size 1.651 1.27)
			(layers "F.Cu" "F.Mask" "F.Paste")
			(net "P12V_HDD0")
		)
		(pad "2" smd rect
			(at 0 1.397 180)
			(size 1.651 1.27)
			(layers "F.Cu" "F.Mask" "F.Paste")
			(net "GND")
		)
	)
	(footprint ""
		(layer "F.Cu")
		(at 219.583 -497.6876 180)
		(property "Reference" "C115"
			(at 0 0 180)
			(layer "F.SilkS")
			(hide yes)
			(effects
				(font
					(size 1.27 1.27)
				)
			)
		)
		(property "Value" "SC1U25V3KX-1-GP"
			(at 0 -2.8194 180)
			(unlocked yes)
			(layer "F.Fab")
			(hide yes)
			(effects
				(font
					(size 1.016 1.016)
					(thickness 0.1524)
				)
			)
		)
		(property "Device Type" "C603H36"
			(at 0 -4.3434 180)
			(unlocked yes)
			(layer "F.Fab")
			(hide yes)
			(effects
				(font
					(size 1.016 1.016)
					(thickness 0.1524)
				)
			)
		)
		(duplicate_pad_numbers_are_jumpers no)
		(fp_line
			(start 0.508 0)
			(end -0.508 0)
			(stroke
				(width 0.2032)
				(type default)
			)
			(layer "F.SilkS")
		)
		(fp_rect
			(start -0.5842 1.3335)
			(end 0.5842 -1.3335)
			(stroke
				(width 0)
				(type default)
			)
			(fill no)
			(layer "F.CrtYd")
		)
		(fp_rect
			(start -0.5842 1.3335)
			(end 0.5842 -1.3335)
			(stroke
				(width 0)
				(type default)
			)
			(fill no)
			(layer "F.Fab")
		)
		(pad "1" smd custom
			(at 0 -0.762 180)
			(size 0.2159 0.2159)
			(layers "F.Cu" "F.Mask" "F.Paste")
			(net "P12V_HDD0")
			(options
				(clearance outline)
				(anchor circle)
			)
			(primitives
				(gr_poly
					(pts
						(arc
							(start -0.3302 -0.4318)
							(mid -0.402042 -0.402042)
							(end -0.4318 -0.3302)
						)
						(arc
							(start -0.4318 0.3302)
							(mid -0.402042 0.402042)
							(end -0.3302 0.4318)
						)
						(arc
							(start 0.3302 0.4318)
							(mid 0.402042 0.402042)
							(end 0.4318 0.3302)
						)
						(arc
							(start 0.4318 -0.3302)
							(mid 0.402042 -0.402042)
							(end 0.3302 -0.4318)
						)
					)
					(width 0)
					(fill yes)
				)
			)
		)
		(pad "2" smd custom
			(at 0 0.762 180)
			(size 0.2159 0.2159)
			(layers "F.Cu" "F.Mask" "F.Paste")
			(net "GND")
			(options
				(clearance outline)
				(anchor circle)
			)
			(primitives
				(gr_poly
					(pts
						(arc
							(start -0.3302 -0.4318)
							(mid -0.402042 -0.402042)
							(end -0.4318 -0.3302)
						)
						(arc
							(start -0.4318 0.3302)
							(mid -0.402042 0.402042)
							(end -0.3302 0.4318)
						)
						(arc
							(start 0.3302 0.4318)
							(mid 0.402042 0.402042)
							(end 0.4318 0.3302)
						)
						(arc
							(start 0.4318 -0.3302)
							(mid 0.402042 -0.402042)
							(end 0.3302 -0.4318)
						)
					)
					(width 0)
					(fill yes)
				)
			)
		)
	)
)
